(kicad_pcb
	(version 20260206)
	(generator "pcbnew")
	(generator_version "10.0")
	(general
		(thickness 1.21888)
		(legacy_teardrops no)
	)
	(paper "A4")
	(title_block
		(title "timecard-v8 — TimeCard-DC-V8_EXP.PcbDoc")
		(comment 1 "Time Appliance Project (Time Card) / footprints 283-288 of 288")
	)
	(layers
		(0 "F.Cu" signal "TOP")
		(4 "In1.Cu" signal "SGND")
		(6 "In2.Cu" signal "IN1")
		(8 "In3.Cu" signal "IN2")
		(10 "In4.Cu" signal "SGND1")
		(2 "B.Cu" signal "BOTTOM")
		(9 "F.Adhes" user "F.Adhesive")
		(11 "B.Adhes" user "B.Adhesive")
		(13 "F.Paste" user "Top Paste")
		(15 "B.Paste" user "Bottom Paste")
		(5 "F.SilkS" user "Top Overlay")
		(7 "B.SilkS" user "Bottom Overlay")
		(1 "F.Mask" user "Top Solder")
		(3 "B.Mask" user "Bottom Solder")
		(17 "Dwgs.User" user "User.Drawings")
		(19 "Cmts.User" user "User.Comments")
		(21 "Eco1.User" user "User.Eco1")
		(23 "Eco2.User" user "User.Eco2")
		(25 "Edge.Cuts" user)
		(27 "Margin" user)
		(31 "F.CrtYd" user "Top Courtyard")
		(29 "B.CrtYd" user "Bottom Courtyard")
		(35 "F.Fab" user "Top Component Center")
		(33 "B.Fab" user "Bottom Component Center")
	)
	(footprint "Capacitors:CAPC1005X06N"
		(layer "B.Cu")
		(at 124.5791 151.7886 90)
		(property "Reference" "C49"
			(at 2.41349 -0.156655 270)
			(unlocked yes)
			(layer "B.SilkS")
			(effects
				(font
					(size 0.762 0.762)
					(thickness 0.2286)
				)
				(justify left bottom mirror)
			)
		)
		(property "Value" "CAP_0402_0.1UF_50V"
			(at -3.382645 0.2921 0)
			(unlocked yes)
			(layer "B.SilkS")
			(hide yes)
			(effects
				(font
					(size 0.762 0.762)
					(thickness 0.2286)
				)
				(justify left bottom mirror)
			)
		)
		(sheetname "PCIe_JTAG")
		(sheetfile "PCIe_JTAG.kicad_sch")
		(duplicate_pad_numbers_are_jumpers no)
		(pad "1" smd rect
			(at -0.43 0)
			(size 0.64 0.68)
			(layers "B.Cu" "B.Mask" "B.Paste")
			(net "NetC49_1")
		)
		(pad "2" smd rect
			(at 0.43 0)
			(size 0.64 0.68)
			(layers "B.Cu" "B.Mask" "B.Paste")
			(net "PCIE_TX1_N")
		)
	)
	(footprint "Capacitors:CAPC1005X06N"
		(layer "B.Cu")
		(at 127.5001 151.7886 90)
		(property "Reference" "C50"
			(at 2.41349 -0.766255 270)
			(unlocked yes)
			(layer "B.SilkS")
			(effects
				(font
					(size 0.762 0.762)
					(thickness 0.2286)
				)
				(justify left bottom mirror)
			)
		)
		(property "Value" "CAP_0402_0.1UF_50V"
			(at -3.382645 0.2921 0)
			(unlocked yes)
			(layer "B.SilkS")
			(hide yes)
			(effects
				(font
					(size 0.762 0.762)
					(thickness 0.2286)
				)
				(justify left bottom mirror)
			)
		)
		(sheetname "PCIe_JTAG")
		(sheetfile "PCIe_JTAG.kicad_sch")
		(duplicate_pad_numbers_are_jumpers no)
		(pad "1" smd rect
			(at -0.43 0)
			(size 0.64 0.68)
			(layers "B.Cu" "B.Mask" "B.Paste")
			(net "NetC50_1")
		)
		(pad "2" smd rect
			(at 0.43 0)
			(size 0.64 0.68)
			(layers "B.Cu" "B.Mask" "B.Paste")
			(net "PCIE_TX2_P")
		)
	)
	(footprint "Capacitors:CAPC1005X06N"
		(layer "B.Cu")
		(at 119.6769 151.7886 90)
		(property "Reference" "C47"
			(at 2.41349 0.097345 270)
			(unlocked yes)
			(layer "B.SilkS")
			(effects
				(font
					(size 0.762 0.762)
					(thickness 0.2286)
				)
				(justify left bottom mirror)
			)
		)
		(property "Value" "CAP_0402_0.1UF_50V"
			(at -3.382645 0.2921 0)
			(unlocked yes)
			(layer "B.SilkS")
			(hide yes)
			(effects
				(font
					(size 0.762 0.762)
					(thickness 0.2286)
				)
				(justify left bottom mirror)
			)
		)
		(sheetname "PCIe_JTAG")
		(sheetfile "PCIe_JTAG.kicad_sch")
		(duplicate_pad_numbers_are_jumpers no)
		(pad "1" smd rect
			(at -0.43 0)
			(size 0.64 0.68)
			(layers "B.Cu" "B.Mask" "B.Paste")
			(net "NetC47_1")
		)
		(pad "2" smd rect
			(at 0.43 0)
			(size 0.64 0.68)
			(layers "B.Cu" "B.Mask" "B.Paste")
			(net "PCIE_TX0_N")
		)
	)
	(footprint "Capacitors:CAPC1005X06N"
		(layer "B.Cu")
		(at 115.5621 151.7886 90)
		(property "Reference" "C44"
			(at 2.885 -1.204345 270)
			(unlocked yes)
			(layer "B.SilkS")
			(effects
				(font
					(size 0.762 0.762)
					(thickness 0.2286)
				)
				(justify left bottom mirror)
			)
		)
		(property "Value" "CAP_0402_0.1UF_50V"
			(at -3.382645 0.2921 0)
			(unlocked yes)
			(layer "B.SilkS")
			(hide yes)
			(effects
				(font
					(size 0.762 0.762)
					(thickness 0.2286)
				)
				(justify left bottom mirror)
			)
		)
		(sheetname "PCIe_JTAG")
		(sheetfile "PCIe_JTAG.kicad_sch")
		(duplicate_pad_numbers_are_jumpers no)
		(pad "1" smd rect
			(at -0.43 0)
			(size 0.64 0.68)
			(layers "B.Cu" "B.Mask" "B.Paste")
			(net "NetC44_1")
		)
		(pad "2" smd rect
			(at 0.43 0)
			(size 0.64 0.68)
			(layers "B.Cu" "B.Mask" "B.Paste")
			(net "PCIE_CLK_P")
		)
	)
	(footprint "Capacitors:CAPC1005X06N"
		(layer "B.Cu")
		(at 118.5847 151.7886 90)
		(property "Reference" "C46"
			(at 2.41349 -0.563055 270)
			(unlocked yes)
			(layer "B.SilkS")
			(effects
				(font
					(size 0.762 0.762)
					(thickness 0.2286)
				)
				(justify left bottom mirror)
			)
		)
		(property "Value" "CAP_0402_0.1UF_50V"
			(at -3.382645 0.2921 0)
			(unlocked yes)
			(layer "B.SilkS")
			(hide yes)
			(effects
				(font
					(size 0.762 0.762)
					(thickness 0.2286)
				)
				(justify left bottom mirror)
			)
		)
		(sheetname "PCIe_JTAG")
		(sheetfile "PCIe_JTAG.kicad_sch")
		(duplicate_pad_numbers_are_jumpers no)
		(pad "1" smd rect
			(at -0.43 0)
			(size 0.64 0.68)
			(layers "B.Cu" "B.Mask" "B.Paste")
			(net "NetC46_1")
		)
		(pad "2" smd rect
			(at 0.43 0)
			(size 0.64 0.68)
			(layers "B.Cu" "B.Mask" "B.Paste")
			(net "PCIE_TX0_P")
		)
	)
	(footprint "Capacitors:CAPC1005X06N"
		(layer "B.Cu")
		(at 123.5631 151.7886 90)
		(property "Reference" "C48"
			(at 2.41349 -0.867855 270)
			(unlocked yes)
			(layer "B.SilkS")
			(effects
				(font
					(size 0.762 0.762)
					(thickness 0.2286)
				)
				(justify left bottom mirror)
			)
		)
		(property "Value" "CAP_0402_0.1UF_50V"
			(at -3.382645 0.2921 0)
			(unlocked yes)
			(layer "B.SilkS")
			(hide yes)
			(effects
				(font
					(size 0.762 0.762)
					(thickness 0.2286)
				)
				(justify left bottom mirror)
			)
		)
		(sheetname "PCIe_JTAG")
		(sheetfile "PCIe_JTAG.kicad_sch")
		(duplicate_pad_numbers_are_jumpers no)
		(pad "1" smd rect
			(at -0.43 0)
			(size 0.64 0.68)
			(layers "B.Cu" "B.Mask" "B.Paste")
			(net "NetC48_1")
		)
		(pad "2" smd rect
			(at 0.43 0)
			(size 0.64 0.68)
			(layers "B.Cu" "B.Mask" "B.Paste")
			(net "PCIE_TX1_P")
		)
	)
)
